(kicad_pcb
	(version 20260206)
	(generator "pcbnew")
	(generator_version "10.0")
	(general
		(thickness 1.6)
		(legacy_teardrops no)
	)
	(paper "A4")
	(title_block
		(title "04192023_DAF0TMB3IC0_F0TG_MB_C_brd_V02_OCP.brd")
		(comment 1 "Grand Teton / footprint 2783 of 8354 (U26), pads 328-434 of 6102")
	)
	(layers
		(0 "F.Cu" signal "TOP")
		(4 "In1.Cu" signal "GND")
		(6 "In2.Cu" signal "IN1")
		(8 "In3.Cu" signal "GND1")
		(10 "In4.Cu" signal "IN2")
		(12 "In5.Cu" signal "GND2")
		(14 "In6.Cu" signal "IN3")
		(16 "In7.Cu" signal "GND3")
		(18 "In8.Cu" signal "VCC")
		(20 "In9.Cu" signal "VCC1")
		(22 "In10.Cu" signal "GND4")
		(24 "In11.Cu" signal "IN4")
		(26 "In12.Cu" signal "GND5")
		(28 "In13.Cu" signal "IN5")
		(30 "In14.Cu" signal "GND6")
		(32 "In15.Cu" signal "IN6")
		(34 "In16.Cu" signal "GND7")
		(2 "B.Cu" signal "BOTTOM")
		(9 "F.Adhes" user "F.Adhesive")
		(11 "B.Adhes" user "B.Adhesive")
		(13 "F.Paste" user "Package Geometry/Pastemask Top")
		(15 "B.Paste" user "Package Geometry/Pastemask Bottom")
		(5 "F.SilkS" user "Ref Des/Silkscreen Top")
		(7 "B.SilkS" user "Ref Des/Silkscreen Bottom")
		(1 "F.Mask" user "Board Geometry/Soldermask Top")
		(3 "B.Mask" user "Board Geometry/Soldermask Bottom")
		(17 "Dwgs.User" user "User.Drawings")
		(19 "Cmts.User" user "User.Comments")
		(21 "Eco1.User" user "User.Eco1")
		(23 "Eco2.User" user "User.Eco2")
		(25 "Edge.Cuts" user "Board Geometry/Outline")
		(27 "Margin" user)
		(31 "F.CrtYd" user "Package Geometry/Place Bound Top")
		(29 "B.CrtYd" user "Package Geometry/Place Bound Bottom")
		(35 "F.Fab" user "Ref Des/Assembly Top")
		(33 "B.Fab" user "Ref Des/Assembly Bottom")
	)
	(footprint ""
		(layer "F.Cu")
		(at 111.927894 -258.880356 180)
		(property "Reference" "U26"
			(at -45.05579 -61.794136 0)
			(unlocked yes)
			(layer "F.SilkS")
			(effects
				(font
					(size 0.7874 0.5842)
					(thickness 0.1524)
				)
			)
		)
		(property "Value" ""
			(at 0 0 180)
			(layer "F.Fab")
			(effects
				(font
					(size 1.27 1.27)
				)
			)
		)
		(duplicate_pad_numbers_are_jumpers no)
		(pad "AD52" smd circle
			(at 13.310108 -18.18005 180)
			(size 0.450088 0.450088)
			(layers "F.Cu" "F.Mask" "F.Paste")
			(net "GND")
		)
		(pad "AD53" smd circle
			(at 14.249908 -18.18005 180)
			(size 0.450088 0.450088)
			(layers "F.Cu" "F.Mask" "F.Paste")
			(net "GND")
		)
		(pad "AD54" smd circle
			(at 15.189962 -18.18005 180)
			(size 0.450088 0.450088)
			(layers "F.Cu" "F.Mask" "F.Paste")
			(net "PVDDIO_P1")
		)
		(pad "AD55" smd circle
			(at 16.130016 -18.18005 180)
			(size 0.450088 0.450088)
			(layers "F.Cu" "F.Mask" "F.Paste")
			(net "M_C_CPU1_SA_DQ<25>")
		)
		(pad "AD56" smd circle
			(at 17.07007 -18.18005 180)
			(size 0.450088 0.450088)
			(layers "F.Cu" "F.Mask" "F.Paste")
			(net "M_C_CPU1_SA_DQ<26>")
		)
		(pad "AD57" smd circle
			(at 18.010124 -18.18005 180)
			(size 0.450088 0.450088)
			(layers "F.Cu" "F.Mask" "F.Paste")
			(net "GND")
		)
		(pad "AD58" smd circle
			(at 18.949924 -18.18005 180)
			(size 0.450088 0.450088)
			(layers "F.Cu" "F.Mask" "F.Paste")
			(net "M_D_CPU1_SA_DQ<25>")
		)
		(pad "AD59" smd circle
			(at 19.889978 -18.18005 180)
			(size 0.450088 0.450088)
			(layers "F.Cu" "F.Mask" "F.Paste")
			(net "GND")
		)
		(pad "AD60" smd circle
			(at 20.830032 -18.18005 180)
			(size 0.450088 0.450088)
			(layers "F.Cu" "F.Mask" "F.Paste")
			(net "M_D_CPU1_SA_DQ<26>")
		)
		(pad "AD61" smd circle
			(at 21.770086 -18.18005 180)
			(size 0.450088 0.450088)
			(layers "F.Cu" "F.Mask" "F.Paste")
			(net "GND")
		)
		(pad "AD62" smd circle
			(at 22.709886 -18.18005 180)
			(size 0.450088 0.450088)
			(layers "F.Cu" "F.Mask" "F.Paste")
			(net "M_B_CPU1_SA_DQ<25>")
		)
		(pad "AD63" smd circle
			(at 23.64994 -18.18005 180)
			(size 0.450088 0.450088)
			(layers "F.Cu" "F.Mask" "F.Paste")
			(net "M_B_CPU1_SA_DQ<26>")
		)
		(pad "AD64" smd circle
			(at 24.589994 -18.18005 180)
			(size 0.450088 0.450088)
			(layers "F.Cu" "F.Mask" "F.Paste")
			(net "GND")
		)
		(pad "AD65" smd circle
			(at 25.530048 -18.18005 180)
			(size 0.450088 0.450088)
			(layers "F.Cu" "F.Mask" "F.Paste")
			(net "M_F_CPU1_SA_DQ<25>")
		)
		(pad "AD66" smd circle
			(at 26.470102 -18.18005 180)
			(size 0.450088 0.450088)
			(layers "F.Cu" "F.Mask" "F.Paste")
			(net "GND")
		)
		(pad "AD67" smd circle
			(at 27.409902 -18.18005 180)
			(size 0.450088 0.450088)
			(layers "F.Cu" "F.Mask" "F.Paste")
			(net "M_F_CPU1_SA_DQ<26>")
		)
		(pad "AD68" smd circle
			(at 28.349956 -18.18005 180)
			(size 0.450088 0.450088)
			(layers "F.Cu" "F.Mask" "F.Paste")
			(net "GND")
		)
		(pad "AD69" smd circle
			(at 29.29001 -18.18005 180)
			(size 0.450088 0.450088)
			(layers "F.Cu" "F.Mask" "F.Paste")
			(net "M_E_CPU1_SA_DQ<25>")
		)
		(pad "AD70" smd circle
			(at 30.230064 -18.18005 180)
			(size 0.450088 0.450088)
			(layers "F.Cu" "F.Mask" "F.Paste")
			(net "M_E_CPU1_SA_DQ<26>")
		)
		(pad "AD71" smd circle
			(at 31.170118 -18.18005 180)
			(size 0.450088 0.450088)
			(layers "F.Cu" "F.Mask" "F.Paste")
			(net "GND")
		)
		(pad "AD72" smd circle
			(at 32.109918 -18.18005 180)
			(size 0.450088 0.450088)
			(layers "F.Cu" "F.Mask" "F.Paste")
			(net "M_A_CPU1_SA_DQ<25>")
		)
		(pad "AD73" smd circle
			(at 33.049972 -18.18005 180)
			(size 0.450088 0.450088)
			(layers "F.Cu" "F.Mask" "F.Paste")
			(net "GND")
		)
		(pad "AD74" smd circle
			(at 33.990026 -18.18005 180)
			(size 0.450088 0.450088)
			(layers "F.Cu" "F.Mask" "F.Paste")
			(net "M_A_CPU1_SA_DQ<26>")
		)
		(pad "AE1" smd circle
			(at -34.159952 -17.370044 180)
			(size 0.450088 0.450088)
			(layers "F.Cu" "F.Mask" "F.Paste")
			(net "GND")
		)
		(pad "AE2" smd circle
			(at -33.219898 -17.370044 180)
			(size 0.450088 0.450088)
			(layers "F.Cu" "F.Mask" "F.Paste")
			(net "M_G_CPU1_SA_DQS_DP<3>")
		)
		(pad "AE3" smd circle
			(at -32.280098 -17.370044 180)
			(size 0.450088 0.450088)
			(layers "F.Cu" "F.Mask" "F.Paste")
			(net "M_G_CPU1_SA_DQ<27>")
		)
		(pad "AE4" smd circle
			(at -31.340044 -17.370044 180)
			(size 0.450088 0.450088)
			(layers "F.Cu" "F.Mask" "F.Paste")
			(net "GND")
		)
		(pad "AE5" smd circle
			(at -30.39999 -17.370044 180)
			(size 0.450088 0.450088)
			(layers "F.Cu" "F.Mask" "F.Paste")
			(net "M_K_CPU1_SA_DQS_DP<3>")
		)
		(pad "AE6" smd circle
			(at -29.459936 -17.370044 180)
			(size 0.450088 0.450088)
			(layers "F.Cu" "F.Mask" "F.Paste")
			(net "GND")
		)
		(pad "AE7" smd circle
			(at -28.519882 -17.370044 180)
			(size 0.450088 0.450088)
			(layers "F.Cu" "F.Mask" "F.Paste")
			(net "M_K_CPU1_SA_DQ<27>")
		)
		(pad "AE8" smd circle
			(at -27.580082 -17.370044 180)
			(size 0.450088 0.450088)
			(layers "F.Cu" "F.Mask" "F.Paste")
			(net "GND")
		)
		(pad "AE9" smd circle
			(at -26.640028 -17.370044 180)
			(size 0.450088 0.450088)
			(layers "F.Cu" "F.Mask" "F.Paste")
			(net "M_L_CPU1_SA_DQS_DP<3>")
		)
		(pad "AE10" smd circle
			(at -25.699974 -17.370044 180)
			(size 0.450088 0.450088)
			(layers "F.Cu" "F.Mask" "F.Paste")
			(net "M_L_CPU1_SA_DQ<27>")
		)
		(pad "AE11" smd circle
			(at -24.75992 -17.370044 180)
			(size 0.450088 0.450088)
			(layers "F.Cu" "F.Mask" "F.Paste")
			(net "GND")
		)
		(pad "AE12" smd circle
			(at -23.82012 -17.370044 180)
			(size 0.450088 0.450088)
			(layers "F.Cu" "F.Mask" "F.Paste")
			(net "M_H_CPU1_SA_DQS_DP<3>")
		)
		(pad "AE13" smd circle
			(at -22.880066 -17.370044 180)
			(size 0.450088 0.450088)
			(layers "F.Cu" "F.Mask" "F.Paste")
			(net "GND")
		)
		(pad "AE14" smd circle
			(at -21.940012 -17.370044 180)
			(size 0.450088 0.450088)
			(layers "F.Cu" "F.Mask" "F.Paste")
			(net "M_H_CPU1_SA_DQ<27>")
		)
		(pad "AE15" smd circle
			(at -20.999958 -17.370044 180)
			(size 0.450088 0.450088)
			(layers "F.Cu" "F.Mask" "F.Paste")
			(net "GND")
		)
		(pad "AE16" smd circle
			(at -20.059904 -17.370044 180)
			(size 0.450088 0.450088)
			(layers "F.Cu" "F.Mask" "F.Paste")
			(net "M_J_CPU1_SA_DQS_DP<3>")
		)
		(pad "AE17" smd circle
			(at -19.120104 -17.370044 180)
			(size 0.450088 0.450088)
			(layers "F.Cu" "F.Mask" "F.Paste")
			(net "M_J_CPU1_SA_DQ<27>")
		)
		(pad "AE18" smd circle
			(at -18.18005 -17.370044 180)
			(size 0.450088 0.450088)
			(layers "F.Cu" "F.Mask" "F.Paste")
			(net "GND")
		)
		(pad "AE19" smd circle
			(at -17.239996 -17.370044 180)
			(size 0.450088 0.450088)
			(layers "F.Cu" "F.Mask" "F.Paste")
			(net "M_I_CPU1_SA_DQS_DP<3>")
		)
		(pad "AE20" smd circle
			(at -16.299942 -17.370044 180)
			(size 0.450088 0.450088)
			(layers "F.Cu" "F.Mask" "F.Paste")
			(net "GND")
		)
		(pad "AE21" smd circle
			(at -15.359888 -17.370044 180)
			(size 0.450088 0.450088)
			(layers "F.Cu" "F.Mask" "F.Paste")
			(net "M_I_CPU1_SA_DQ<27>")
		)
		(pad "AE22" smd circle
			(at -14.420088 -17.370044 180)
			(size 0.450088 0.450088)
			(layers "F.Cu" "F.Mask" "F.Paste")
			(net "GND")
		)
		(pad "AE23" smd circle
			(at -13.480034 -17.370044 180)
			(size 0.450088 0.450088)
			(layers "F.Cu" "F.Mask" "F.Paste")
			(net "GMI_CPU0_G0_CPU1_G2_TX_DN<15>")
		)
		(pad "AE24" smd circle
			(at -12.53998 -17.370044 180)
			(size 0.450088 0.450088)
			(layers "F.Cu" "F.Mask" "F.Paste")
			(net "GMI_CPU0_G0_CPU1_G2_TX_DP<15>")
		)
		(pad "AE25" smd circle
			(at -11.599926 -17.370044 180)
			(size 0.450088 0.450088)
			(layers "F.Cu" "F.Mask" "F.Paste")
			(net "GND")
		)
		(pad "AE26" smd circle
			(at -10.659872 -17.370044 180)
			(size 0.450088 0.450088)
			(layers "F.Cu" "F.Mask" "F.Paste")
			(net "GMI_CPU0_G0_CPU1_G2_TX_DN<12>")
		)
		(pad "AE27" smd circle
			(at -9.720072 -17.370044 180)
			(size 0.450088 0.450088)
			(layers "F.Cu" "F.Mask" "F.Paste")
			(net "GMI_CPU0_G0_CPU1_G2_TX_DP<12>")
		)
		(pad "AE28" smd circle
			(at -8.780018 -17.370044 180)
			(size 0.450088 0.450088)
			(layers "F.Cu" "F.Mask" "F.Paste")
			(net "GND")
		)
		(pad "AE29" smd circle
			(at -7.839964 -17.370044 180)
			(size 0.450088 0.450088)
			(layers "F.Cu" "F.Mask" "F.Paste")
			(net "GMI_CPU0_G0_CPU1_G2_TX_DN<9>")
		)
		(pad "AE30" smd circle
			(at -6.89991 -17.370044 180)
			(size 0.450088 0.450088)
			(layers "F.Cu" "F.Mask" "F.Paste")
			(net "GMI_CPU0_G0_CPU1_G2_TX_DP<9>")
		)
		(pad "AE31" smd circle
			(at -5.96011 -17.370044 180)
			(size 0.450088 0.450088)
			(layers "F.Cu" "F.Mask" "F.Paste")
			(net "GND")
		)
		(pad "AE32" smd circle
			(at -5.020056 -17.370044 180)
			(size 0.450088 0.450088)
			(layers "F.Cu" "F.Mask" "F.Paste")
			(net "GMI_CPU0_G0_CPU1_G2_TX_DN<6>")
		)
		(pad "AE33" smd circle
			(at -4.080002 -17.370044 180)
			(size 0.450088 0.450088)
			(layers "F.Cu" "F.Mask" "F.Paste")
			(net "GMI_CPU0_G0_CPU1_G2_TX_DP<6>")
		)
		(pad "AE34" smd circle
			(at -3.139948 -17.370044 180)
			(size 0.450088 0.450088)
			(layers "F.Cu" "F.Mask" "F.Paste")
			(net "GND")
		)
		(pad "AE35" smd circle
			(at -2.199894 -17.370044 180)
			(size 0.450088 0.450088)
			(layers "F.Cu" "F.Mask" "F.Paste")
			(net "GND")
		)
		(pad "AE36" smd circle
			(at -1.260094 -17.370044 180)
			(size 0.450088 0.450088)
			(layers "F.Cu" "F.Mask" "F.Paste")
			(net "GND")
		)
		(pad "AE40" smd circle
			(at 1.560068 -17.370044 180)
			(size 0.450088 0.450088)
			(layers "F.Cu" "F.Mask" "F.Paste")
			(net "GND")
		)
		(pad "AE41" smd circle
			(at 2.500122 -17.370044 180)
			(size 0.450088 0.450088)
			(layers "F.Cu" "F.Mask" "F.Paste")
			(net "GND")
		)
		(pad "AE42" smd circle
			(at 3.439922 -17.370044 180)
			(size 0.450088 0.450088)
			(layers "F.Cu" "F.Mask" "F.Paste")
			(net "GND")
		)
		(pad "AE43" smd circle
			(at 4.379976 -17.370044 180)
			(size 0.450088 0.450088)
			(layers "F.Cu" "F.Mask" "F.Paste")
			(net "GMI_CPU1_G0_CPU0_G2_TX_DP<9>")
		)
		(pad "AE44" smd circle
			(at 5.32003 -17.370044 180)
			(size 0.450088 0.450088)
			(layers "F.Cu" "F.Mask" "F.Paste")
			(net "GMI_CPU1_G0_CPU0_G2_TX_DN<9>")
		)
		(pad "AE45" smd circle
			(at 6.260084 -17.370044 180)
			(size 0.450088 0.450088)
			(layers "F.Cu" "F.Mask" "F.Paste")
			(net "GND")
		)
		(pad "AE46" smd circle
			(at 7.199884 -17.370044 180)
			(size 0.450088 0.450088)
			(layers "F.Cu" "F.Mask" "F.Paste")
			(net "GMI_CPU1_G0_CPU0_G2_TX_DP<6>")
		)
		(pad "AE47" smd circle
			(at 8.139938 -17.370044 180)
			(size 0.450088 0.450088)
			(layers "F.Cu" "F.Mask" "F.Paste")
			(net "GMI_CPU1_G0_CPU0_G2_TX_DN<6>")
		)
		(pad "AE48" smd circle
			(at 9.079992 -17.370044 180)
			(size 0.450088 0.450088)
			(layers "F.Cu" "F.Mask" "F.Paste")
			(net "GND")
		)
		(pad "AE49" smd circle
			(at 10.020046 -17.370044 180)
			(size 0.450088 0.450088)
			(layers "F.Cu" "F.Mask" "F.Paste")
			(net "GMI_CPU1_G0_CPU0_G2_TX_DP<3>")
		)
		(pad "AE50" smd circle
			(at 10.9601 -17.370044 180)
			(size 0.450088 0.450088)
			(layers "F.Cu" "F.Mask" "F.Paste")
			(net "GMI_CPU1_G0_CPU0_G2_TX_DN<3>")
		)
		(pad "AE51" smd circle
			(at 11.8999 -17.370044 180)
			(size 0.450088 0.450088)
			(layers "F.Cu" "F.Mask" "F.Paste")
			(net "GND")
		)
		(pad "AE52" smd circle
			(at 12.839954 -17.370044 180)
			(size 0.450088 0.450088)
			(layers "F.Cu" "F.Mask" "F.Paste")
			(net "GMI_CPU1_G0_CPU0_G2_TX_DP<0>")
		)
		(pad "AE53" smd circle
			(at 13.780008 -17.370044 180)
			(size 0.450088 0.450088)
			(layers "F.Cu" "F.Mask" "F.Paste")
			(net "GMI_CPU1_G0_CPU0_G2_TX_DN<0>")
		)
		(pad "AE54" smd circle
			(at 14.720062 -17.370044 180)
			(size 0.450088 0.450088)
			(layers "F.Cu" "F.Mask" "F.Paste")
			(net "GND")
		)
		(pad "AE55" smd circle
			(at 15.660116 -17.370044 180)
			(size 0.450088 0.450088)
			(layers "F.Cu" "F.Mask" "F.Paste")
			(net "M_C_CPU1_SA_DQ<27>")
		)
		(pad "AE56" smd circle
			(at 16.599916 -17.370044 180)
			(size 0.450088 0.450088)
			(layers "F.Cu" "F.Mask" "F.Paste")
			(net "GND")
		)
		(pad "AE57" smd circle
			(at 17.53997 -17.370044 180)
			(size 0.450088 0.450088)
			(layers "F.Cu" "F.Mask" "F.Paste")
			(net "M_C_CPU1_SA_DQS_DP<3>")
		)
		(pad "AE58" smd circle
			(at 18.480024 -17.370044 180)
			(size 0.450088 0.450088)
			(layers "F.Cu" "F.Mask" "F.Paste")
			(net "GND")
		)
		(pad "AE59" smd circle
			(at 19.420078 -17.370044 180)
			(size 0.450088 0.450088)
			(layers "F.Cu" "F.Mask" "F.Paste")
			(net "M_D_CPU1_SA_DQ<27>")
		)
		(pad "AE60" smd circle
			(at 20.359878 -17.370044 180)
			(size 0.450088 0.450088)
			(layers "F.Cu" "F.Mask" "F.Paste")
			(net "M_D_CPU1_SA_DQS_DP<3>")
		)
		(pad "AE61" smd circle
			(at 21.299932 -17.370044 180)
			(size 0.450088 0.450088)
			(layers "F.Cu" "F.Mask" "F.Paste")
			(net "GND")
		)
		(pad "AE62" smd circle
			(at 22.239986 -17.370044 180)
			(size 0.450088 0.450088)
			(layers "F.Cu" "F.Mask" "F.Paste")
			(net "M_B_CPU1_SA_DQ<27>")
		)
		(pad "AE63" smd circle
			(at 23.18004 -17.370044 180)
			(size 0.450088 0.450088)
			(layers "F.Cu" "F.Mask" "F.Paste")
			(net "GND")
		)
		(pad "AE64" smd circle
			(at 24.120094 -17.370044 180)
			(size 0.450088 0.450088)
			(layers "F.Cu" "F.Mask" "F.Paste")
			(net "M_B_CPU1_SA_DQS_DP<3>")
		)
		(pad "AE65" smd circle
			(at 25.059894 -17.370044 180)
			(size 0.450088 0.450088)
			(layers "F.Cu" "F.Mask" "F.Paste")
			(net "GND")
		)
		(pad "AE66" smd circle
			(at 25.999948 -17.370044 180)
			(size 0.450088 0.450088)
			(layers "F.Cu" "F.Mask" "F.Paste")
			(net "M_F_CPU1_SA_DQ<27>")
		)
		(pad "AE67" smd circle
			(at 26.940002 -17.370044 180)
			(size 0.450088 0.450088)
			(layers "F.Cu" "F.Mask" "F.Paste")
			(net "M_F_CPU1_SA_DQS_DP<3>")
		)
		(pad "AE68" smd circle
			(at 27.880056 -17.370044 180)
			(size 0.450088 0.450088)
			(layers "F.Cu" "F.Mask" "F.Paste")
			(net "GND")
		)
		(pad "AE69" smd circle
			(at 28.82011 -17.370044 180)
			(size 0.450088 0.450088)
			(layers "F.Cu" "F.Mask" "F.Paste")
			(net "M_E_CPU1_SA_DQ<27>")
		)
		(pad "AE70" smd circle
			(at 29.75991 -17.370044 180)
			(size 0.450088 0.450088)
			(layers "F.Cu" "F.Mask" "F.Paste")
			(net "GND")
		)
		(pad "AE71" smd circle
			(at 30.699964 -17.370044 180)
			(size 0.450088 0.450088)
			(layers "F.Cu" "F.Mask" "F.Paste")
			(net "M_E_CPU1_SA_DQS_DP<3>")
		)
		(pad "AE72" smd circle
			(at 31.640018 -17.370044 180)
			(size 0.450088 0.450088)
			(layers "F.Cu" "F.Mask" "F.Paste")
			(net "GND")
		)
		(pad "AE73" smd circle
			(at 32.580072 -17.370044 180)
			(size 0.450088 0.450088)
			(layers "F.Cu" "F.Mask" "F.Paste")
			(net "M_A_CPU1_SA_DQ<27>")
		)
		(pad "AE74" smd circle
			(at 33.519872 -17.370044 180)
			(size 0.450088 0.450088)
			(layers "F.Cu" "F.Mask" "F.Paste")
			(net "M_A_CPU1_SA_DQS_DP<3>")
		)
		(pad "AE75" smd circle
			(at 34.459926 -17.370044 180)
			(size 0.450088 0.450088)
			(layers "F.Cu" "F.Mask" "F.Paste")
			(net "GND")
		)
		(pad "AF2" smd circle
			(at -33.690052 -16.560038 180)
			(size 0.450088 0.450088)
			(layers "F.Cu" "F.Mask" "F.Paste")
			(net "M_G_CPU1_SA_DQS_DN<3>")
		)
		(pad "AF3" smd circle
			(at -32.749998 -16.560038 180)
			(size 0.450088 0.450088)
			(layers "F.Cu" "F.Mask" "F.Paste")
			(net "GND")
		)
		(pad "AF4" smd circle
			(at -31.809944 -16.560038 180)
			(size 0.450088 0.450088)
			(layers "F.Cu" "F.Mask" "F.Paste")
			(net "M_G_CPU1_SA_DQS_DN<8>")
		)
		(pad "AF5" smd circle
			(at -30.86989 -16.560038 180)
			(size 0.450088 0.450088)
			(layers "F.Cu" "F.Mask" "F.Paste")
			(net "PVDDCR_SOC_P1")
		)
		(pad "AF6" smd circle
			(at -29.93009 -16.560038 180)
			(size 0.450088 0.450088)
			(layers "F.Cu" "F.Mask" "F.Paste")
			(net "M_K_CPU1_SA_DQS_DN<3>")
		)
		(pad "AF7" smd circle
			(at -28.990036 -16.560038 180)
			(size 0.450088 0.450088)
			(layers "F.Cu" "F.Mask" "F.Paste")
			(net "M_K_CPU1_SA_DQS_DN<8>")
		)
		(pad "AF8" smd circle
			(at -28.049982 -16.560038 180)
			(size 0.450088 0.450088)
			(layers "F.Cu" "F.Mask" "F.Paste")
			(net "GND")
		)
		(pad "AF9" smd circle
			(at -27.109928 -16.560038 180)
			(size 0.450088 0.450088)
			(layers "F.Cu" "F.Mask" "F.Paste")
			(net "M_L_CPU1_SA_DQS_DN<3>")
		)
		(pad "AF10" smd circle
			(at -26.170128 -16.560038 180)
			(size 0.450088 0.450088)
			(layers "F.Cu" "F.Mask" "F.Paste")
			(net "GND")
		)
		(pad "AF11" smd circle
			(at -25.230074 -16.560038 180)
			(size 0.450088 0.450088)
			(layers "F.Cu" "F.Mask" "F.Paste")
			(net "M_L_CPU1_SA_DQS_DN<8>")
		)
		(pad "AF12" smd circle
			(at -24.29002 -16.560038 180)
			(size 0.450088 0.450088)
			(layers "F.Cu" "F.Mask" "F.Paste")
			(net "PVDDCR_SOC_P1")
		)
		(pad "AF13" smd circle
			(at -23.349966 -16.560038 180)
			(size 0.450088 0.450088)
			(layers "F.Cu" "F.Mask" "F.Paste")
			(net "M_H_CPU1_SA_DQS_DN<3>")
		)
	)
)
